(kicad_pcb
	(version 20260206)
	(generator "pcbnew")
	(generator_version "10.0")
	(general
		(thickness 1.6)
		(legacy_teardrops no)
	)
	(paper "A4")
	(title_block
		(title "baseboard — 13948-1b.1110WZS1818.brd")
		(comment 1 "Honey Badger (Wiwynn) / footprints 1435-1442 of 2523")
	)
	(layers
		(0 "F.Cu" signal "TOP")
		(4 "In1.Cu" signal "L2GND")
		(6 "In2.Cu" signal "L3")
		(8 "In3.Cu" signal "L4VCC")
		(10 "In4.Cu" signal "L5VCC")
		(12 "In5.Cu" signal "L6")
		(14 "In6.Cu" signal "L7GND")
		(2 "B.Cu" signal "BOTTOM")
		(9 "F.Adhes" user "F.Adhesive")
		(11 "B.Adhes" user "B.Adhesive")
		(13 "F.Paste" user "Package Geometry/Pastemask Top")
		(15 "B.Paste" user "Package Geometry/Pastemask Bottom")
		(5 "F.SilkS" user "Ref Des/Silkscreen Top")
		(7 "B.SilkS" user "Ref Des/Silkscreen Bottom")
		(1 "F.Mask" user "Board Geometry/Soldermask Top")
		(3 "B.Mask" user "Board Geometry/Soldermask Bottom")
		(17 "Dwgs.User" user "User.Drawings")
		(19 "Cmts.User" user "User.Comments")
		(21 "Eco1.User" user "User.Eco1")
		(23 "Eco2.User" user "User.Eco2")
		(25 "Edge.Cuts" user "Board Geometry/Outline")
		(27 "Margin" user)
		(31 "F.CrtYd" user "Package Geometry/Place Bound Top")
		(29 "B.CrtYd" user "Package Geometry/Place Bound Bottom")
		(35 "F.Fab" user "Ref Des/Assembly Top")
		(33 "B.Fab" user "Ref Des/Assembly Bottom")
	)
	(footprint ""
		(layer "F.Cu")
		(at 219.075 -110.363)
		(property "Reference" "R598"
			(at 0 0 0)
			(layer "F.SilkS")
			(hide yes)
			(effects
				(font
					(size 1.27 1.27)
				)
			)
		)
		(property "Value" "4K75R2F-1-GP"
			(at 0.064008 -3.993896 0)
			(unlocked yes)
			(layer "F.Fab")
			(hide yes)
			(effects
				(font
					(size 1.016 1.016)
					(thickness 0.1524)
				)
			)
		)
		(property "Device Type" "R402H16"
			(at 0.064008 -5.517896 0)
			(unlocked yes)
			(layer "F.Fab")
			(hide yes)
			(effects
				(font
					(size 1.016 1.016)
					(thickness 0.1524)
				)
			)
		)
		(duplicate_pad_numbers_are_jumpers no)
		(fp_line
			(start -0.508 -0.9398)
			(end -0.508 0.9398)
			(stroke
				(width 0.1524)
				(type default)
			)
			(layer "F.SilkS")
		)
		(fp_line
			(start 0.508 -0.9398)
			(end -0.508 -0.9398)
			(stroke
				(width 0.1524)
				(type default)
			)
			(layer "F.SilkS")
		)
		(fp_rect
			(start -0.508 0.9398)
			(end 0.508 -0.9398)
			(stroke
				(width 0)
				(type default)
			)
			(fill no)
			(layer "F.CrtYd")
		)
		(fp_rect
			(start -0.508 0.9398)
			(end 0.508 -0.9398)
			(stroke
				(width 0)
				(type default)
			)
			(fill no)
			(layer "F.Fab")
		)
		(pad "1" smd custom
			(at 0 -0.4445)
			(size 0.1397 0.1397)
			(layers "F.Cu" "F.Mask" "F.Paste")
			(net "P3V3_STBY")
			(options
				(clearance outline)
				(anchor circle)
			)
			(primitives
				(gr_poly
					(pts
						(arc
							(start -0.1778 -0.2794)
							(mid -0.249642 -0.249642)
							(end -0.2794 -0.1778)
						)
						(arc
							(start -0.2794 0.1778)
							(mid -0.249642 0.249642)
							(end -0.1778 0.2794)
						)
						(arc
							(start 0.1778 0.2794)
							(mid 0.249642 0.249642)
							(end 0.2794 0.1778)
						)
						(arc
							(start 0.2794 -0.1778)
							(mid 0.249642 -0.249642)
							(end 0.1778 -0.2794)
						)
					)
					(width 0)
					(fill yes)
				)
			)
		)
		(pad "2" smd custom
			(at 0 0.4445)
			(size 0.1397 0.1397)
			(layers "F.Cu" "F.Mask" "F.Paste")
			(net "TPS74801_1V5_C_EN")
			(options
				(clearance outline)
				(anchor circle)
			)
			(primitives
				(gr_poly
					(pts
						(arc
							(start -0.1778 -0.2794)
							(mid -0.249642 -0.249642)
							(end -0.2794 -0.1778)
						)
						(arc
							(start -0.2794 0.1778)
							(mid -0.249642 0.249642)
							(end -0.1778 0.2794)
						)
						(arc
							(start 0.1778 0.2794)
							(mid 0.249642 0.249642)
							(end 0.2794 0.1778)
						)
						(arc
							(start 0.2794 -0.1778)
							(mid 0.249642 -0.249642)
							(end 0.1778 -0.2794)
						)
					)
					(width 0)
					(fill yes)
				)
			)
		)
	)
	(footprint ""
		(layer "F.Cu")
		(at 188.459872 -195.271136 -90)
		(property "Reference" "R154"
			(at 0 0 270)
			(layer "F.SilkS")
			(hide yes)
			(effects
				(font
					(size 1.27 1.27)
				)
			)
		)
		(property "Value" "0R2J-2-GP"
			(at 0.064008 -3.993896 270)
			(unlocked yes)
			(layer "F.Fab")
			(hide yes)
			(effects
				(font
					(size 1.016 1.016)
					(thickness 0.1524)
				)
			)
		)
		(property "Device Type" "R402H16"
			(at 0.064008 -5.517896 270)
			(unlocked yes)
			(layer "F.Fab")
			(hide yes)
			(effects
				(font
					(size 1.016 1.016)
					(thickness 0.1524)
				)
			)
		)
		(duplicate_pad_numbers_are_jumpers no)
		(fp_line
			(start -0.508 -0.9398)
			(end -0.508 0.9398)
			(stroke
				(width 0.1524)
				(type default)
			)
			(layer "F.SilkS")
		)
		(fp_line
			(start 0.508 -0.9398)
			(end -0.508 -0.9398)
			(stroke
				(width 0.1524)
				(type default)
			)
			(layer "F.SilkS")
		)
		(fp_rect
			(start -0.508 0.9398)
			(end 0.508 -0.9398)
			(stroke
				(width 0)
				(type default)
			)
			(fill no)
			(layer "F.CrtYd")
		)
		(fp_rect
			(start -0.508 0.9398)
			(end 0.508 -0.9398)
			(stroke
				(width 0)
				(type default)
			)
			(fill no)
			(layer "F.Fab")
		)
		(pad "1" smd custom
			(at 0 -0.4445 270)
			(size 0.1397 0.1397)
			(layers "F.Cu" "F.Mask" "F.Paste")
			(net "SAS_I2C_C_BUF_SDA_R")
			(options
				(clearance outline)
				(anchor circle)
			)
			(primitives
				(gr_poly
					(pts
						(arc
							(start -0.1778 -0.2794)
							(mid -0.249642 -0.249642)
							(end -0.2794 -0.1778)
						)
						(arc
							(start -0.2794 0.1778)
							(mid -0.249642 0.249642)
							(end -0.1778 0.2794)
						)
						(arc
							(start 0.1778 0.2794)
							(mid 0.249642 0.249642)
							(end 0.2794 0.1778)
						)
						(arc
							(start 0.2794 -0.1778)
							(mid 0.249642 -0.249642)
							(end 0.1778 -0.2794)
						)
					)
					(width 0)
					(fill yes)
				)
			)
		)
		(pad "2" smd custom
			(at 0 0.4445 270)
			(size 0.1397 0.1397)
			(layers "F.Cu" "F.Mask" "F.Paste")
			(net "SAS_I2C_C_BUF_SDA")
			(options
				(clearance outline)
				(anchor circle)
			)
			(primitives
				(gr_poly
					(pts
						(arc
							(start -0.1778 -0.2794)
							(mid -0.249642 -0.249642)
							(end -0.2794 -0.1778)
						)
						(arc
							(start -0.2794 0.1778)
							(mid -0.249642 0.249642)
							(end -0.1778 0.2794)
						)
						(arc
							(start 0.1778 0.2794)
							(mid 0.249642 0.249642)
							(end 0.2794 0.1778)
						)
						(arc
							(start 0.2794 -0.1778)
							(mid 0.249642 -0.249642)
							(end 0.1778 -0.2794)
						)
					)
					(width 0)
					(fill yes)
				)
			)
		)
	)
	(footprint ""
		(layer "F.Cu")
		(at 52.705 -180.086 180)
		(property "Reference" "SR809"
			(at 0 0 180)
			(layer "F.SilkS")
			(hide yes)
			(effects
				(font
					(size 1.27 1.27)
				)
			)
		)
		(property "Value" "4K75R2F-1-GP"
			(at 0.064008 -3.993896 180)
			(unlocked yes)
			(layer "F.Fab")
			(hide yes)
			(effects
				(font
					(size 1.016 1.016)
					(thickness 0.1524)
				)
			)
		)
		(property "Device Type" "R402H16"
			(at 0.064008 -5.517896 180)
			(unlocked yes)
			(layer "F.Fab")
			(hide yes)
			(effects
				(font
					(size 1.016 1.016)
					(thickness 0.1524)
				)
			)
		)
		(duplicate_pad_numbers_are_jumpers no)
		(fp_line
			(start 0.508 -0.9398)
			(end -0.508 -0.9398)
			(stroke
				(width 0.1524)
				(type default)
			)
			(layer "F.SilkS")
		)
		(fp_line
			(start -0.508 -0.9398)
			(end -0.508 0.9398)
			(stroke
				(width 0.1524)
				(type default)
			)
			(layer "F.SilkS")
		)
		(fp_rect
			(start -0.508 0.9398)
			(end 0.508 -0.9398)
			(stroke
				(width 0)
				(type default)
			)
			(fill no)
			(layer "F.CrtYd")
		)
		(fp_rect
			(start -0.508 0.9398)
			(end 0.508 -0.9398)
			(stroke
				(width 0)
				(type default)
			)
			(fill no)
			(layer "F.Fab")
		)
		(pad "1" smd custom
			(at 0 -0.4445 180)
			(size 0.1397 0.1397)
			(layers "F.Cu" "F.Mask" "F.Paste")
			(net "P1V8_E")
			(options
				(clearance outline)
				(anchor circle)
			)
			(primitives
				(gr_poly
					(pts
						(arc
							(start -0.1778 -0.2794)
							(mid -0.249642 -0.249642)
							(end -0.2794 -0.1778)
						)
						(arc
							(start -0.2794 0.1778)
							(mid -0.249642 0.249642)
							(end -0.1778 0.2794)
						)
						(arc
							(start 0.1778 0.2794)
							(mid 0.249642 0.249642)
							(end 0.2794 0.1778)
						)
						(arc
							(start 0.2794 -0.1778)
							(mid 0.249642 -0.249642)
							(end 0.1778 -0.2794)
						)
					)
					(width 0)
					(fill yes)
				)
			)
		)
		(pad "2" smd custom
			(at 0 0.4445 180)
			(size 0.1397 0.1397)
			(layers "F.Cu" "F.Mask" "F.Paste")
			(net "ICE_TRST_N")
			(options
				(clearance outline)
				(anchor circle)
			)
			(primitives
				(gr_poly
					(pts
						(arc
							(start -0.1778 -0.2794)
							(mid -0.249642 -0.249642)
							(end -0.2794 -0.1778)
						)
						(arc
							(start -0.2794 0.1778)
							(mid -0.249642 0.249642)
							(end -0.1778 0.2794)
						)
						(arc
							(start 0.1778 0.2794)
							(mid 0.249642 0.249642)
							(end 0.2794 0.1778)
						)
						(arc
							(start 0.2794 -0.1778)
							(mid 0.249642 -0.249642)
							(end 0.1778 -0.2794)
						)
					)
					(width 0)
					(fill yes)
				)
			)
		)
	)
	(footprint ""
		(layer "F.Cu")
		(at 23.064216 -202.74788 90)
		(property "Reference" "R570"
			(at 0 0 90)
			(layer "F.SilkS")
			(hide yes)
			(effects
				(font
					(size 1.27 1.27)
				)
			)
		)
		(property "Value" "0R2J-2-GP"
			(at 0.064008 -3.993896 90)
			(unlocked yes)
			(layer "F.Fab")
			(hide yes)
			(effects
				(font
					(size 1.016 1.016)
					(thickness 0.1524)
				)
			)
		)
		(property "Device Type" "R402H16"
			(at 0.064008 -5.517896 90)
			(unlocked yes)
			(layer "F.Fab")
			(hide yes)
			(effects
				(font
					(size 1.016 1.016)
					(thickness 0.1524)
				)
			)
		)
		(duplicate_pad_numbers_are_jumpers no)
		(fp_line
			(start 0.508 -0.9398)
			(end -0.508 -0.9398)
			(stroke
				(width 0.1524)
				(type default)
			)
			(layer "F.SilkS")
		)
		(fp_line
			(start -0.508 -0.9398)
			(end -0.508 0.9398)
			(stroke
				(width 0.1524)
				(type default)
			)
			(layer "F.SilkS")
		)
		(fp_rect
			(start -0.508 0.9398)
			(end 0.508 -0.9398)
			(stroke
				(width 0)
				(type default)
			)
			(fill no)
			(layer "F.CrtYd")
		)
		(fp_rect
			(start -0.508 0.9398)
			(end 0.508 -0.9398)
			(stroke
				(width 0)
				(type default)
			)
			(fill no)
			(layer "F.Fab")
		)
		(pad "1" smd custom
			(at 0 -0.4445 90)
			(size 0.1397 0.1397)
			(layers "F.Cu" "F.Mask" "F.Paste")
			(net "ADC_P0V9_E")
			(options
				(clearance outline)
				(anchor circle)
			)
			(primitives
				(gr_poly
					(pts
						(arc
							(start -0.1778 -0.2794)
							(mid -0.249642 -0.249642)
							(end -0.2794 -0.1778)
						)
						(arc
							(start -0.2794 0.1778)
							(mid -0.249642 0.249642)
							(end -0.1778 0.2794)
						)
						(arc
							(start 0.1778 0.2794)
							(mid 0.249642 0.249642)
							(end 0.2794 0.1778)
						)
						(arc
							(start 0.2794 -0.1778)
							(mid 0.249642 -0.249642)
							(end 0.1778 -0.2794)
						)
					)
					(width 0)
					(fill yes)
				)
			)
		)
		(pad "2" smd custom
			(at 0 0.4445 90)
			(size 0.1397 0.1397)
			(layers "F.Cu" "F.Mask" "F.Paste")
			(net "P0V9_E_SENSE")
			(options
				(clearance outline)
				(anchor circle)
			)
			(primitives
				(gr_poly
					(pts
						(arc
							(start -0.1778 -0.2794)
							(mid -0.249642 -0.249642)
							(end -0.2794 -0.1778)
						)
						(arc
							(start -0.2794 0.1778)
							(mid -0.249642 0.249642)
							(end -0.1778 0.2794)
						)
						(arc
							(start 0.1778 0.2794)
							(mid 0.249642 0.249642)
							(end 0.2794 0.1778)
						)
						(arc
							(start 0.2794 -0.1778)
							(mid 0.249642 -0.249642)
							(end 0.1778 -0.2794)
						)
					)
					(width 0)
					(fill yes)
				)
			)
		)
	)
	(footprint ""
		(layer "F.Cu")
		(at 307.848 -173.99)
		(property "Reference" "TP105"
			(at 0 0 0)
			(layer "F.SilkS")
			(hide yes)
			(effects
				(font
					(size 1.27 1.27)
				)
			)
		)
		(property "Value" "TPAD28"
			(at -0.0127 -1.6637 0)
			(unlocked yes)
			(layer "F.Fab")
			(hide yes)
			(effects
				(font
					(size 1.016 1.016)
					(thickness 0.1524)
				)
			)
		)
		(property "Device Type" "TPAD28"
			(at -0.0127 -3.1877 0)
			(unlocked yes)
			(layer "F.Fab")
			(hide yes)
			(effects
				(font
					(size 1.016 1.016)
					(thickness 0.1524)
				)
			)
		)
		(duplicate_pad_numbers_are_jumpers no)
		(fp_poly
			(pts
				(arc
					(start 0.3556 0)
					(mid -0.3556 0)
					(end 0.3556 0)
				)
			)
			(stroke
				(width 0)
				(type default)
			)
			(fill no)
			(layer "F.CrtYd")
		)
		(fp_poly
			(pts
				(arc
					(start 0.6096 0)
					(mid -0.6096 0)
					(end 0.6096 0)
				)
			)
			(stroke
				(width 0)
				(type default)
			)
			(fill no)
			(layer "F.Fab")
		)
		(pad "1" smd circle
			(at 0 0)
			(size 0.7112 0.7112)
			(layers "F.Cu" "F.Mask" "F.Paste")
			(net "TP_BMC_GPIOQ6")
		)
	)
	(footprint ""
		(layer "F.Cu")
		(at 76.327 -22.733 180)
		(property "Reference" "PR192"
			(at 0 0 180)
			(layer "F.SilkS")
			(hide yes)
			(effects
				(font
					(size 1.27 1.27)
				)
			)
		)
		(property "Value" "0R2J-2-GP"
			(at 0.064008 -3.993896 180)
			(unlocked yes)
			(layer "F.Fab")
			(hide yes)
			(effects
				(font
					(size 1.016 1.016)
					(thickness 0.1524)
				)
			)
		)
		(property "Device Type" "R402H16"
			(at 0.064008 -5.517896 180)
			(unlocked yes)
			(layer "F.Fab")
			(hide yes)
			(effects
				(font
					(size 1.016 1.016)
					(thickness 0.1524)
				)
			)
		)
		(duplicate_pad_numbers_are_jumpers no)
		(fp_line
			(start 0.508 -0.9398)
			(end -0.508 -0.9398)
			(stroke
				(width 0.1524)
				(type default)
			)
			(layer "F.SilkS")
		)
		(fp_line
			(start -0.508 -0.9398)
			(end -0.508 0.9398)
			(stroke
				(width 0.1524)
				(type default)
			)
			(layer "F.SilkS")
		)
		(fp_rect
			(start -0.508 0.9398)
			(end 0.508 -0.9398)
			(stroke
				(width 0)
				(type default)
			)
			(fill no)
			(layer "F.CrtYd")
		)
		(fp_rect
			(start -0.508 0.9398)
			(end 0.508 -0.9398)
			(stroke
				(width 0)
				(type default)
			)
			(fill no)
			(layer "F.Fab")
		)
		(pad "1" smd custom
			(at 0 -0.4445 180)
			(size 0.1397 0.1397)
			(layers "F.Cu" "F.Mask" "F.Paste")
			(net "VT235_EN")
			(options
				(clearance outline)
				(anchor circle)
			)
			(primitives
				(gr_poly
					(pts
						(arc
							(start -0.1778 -0.2794)
							(mid -0.249642 -0.249642)
							(end -0.2794 -0.1778)
						)
						(arc
							(start -0.2794 0.1778)
							(mid -0.249642 0.249642)
							(end -0.1778 0.2794)
						)
						(arc
							(start 0.1778 0.2794)
							(mid 0.249642 0.249642)
							(end 0.2794 0.1778)
						)
						(arc
							(start 0.2794 -0.1778)
							(mid 0.249642 -0.249642)
							(end 0.1778 -0.2794)
						)
					)
					(width 0)
					(fill yes)
				)
			)
		)
		(pad "2" smd custom
			(at 0 0.4445 180)
			(size 0.1397 0.1397)
			(layers "F.Cu" "F.Mask" "F.Paste")
			(net "PWRGD_P1V5_C_PG")
			(options
				(clearance outline)
				(anchor circle)
			)
			(primitives
				(gr_poly
					(pts
						(arc
							(start -0.1778 -0.2794)
							(mid -0.249642 -0.249642)
							(end -0.2794 -0.1778)
						)
						(arc
							(start -0.2794 0.1778)
							(mid -0.249642 0.249642)
							(end -0.1778 0.2794)
						)
						(arc
							(start 0.1778 0.2794)
							(mid 0.249642 0.249642)
							(end 0.2794 0.1778)
						)
						(arc
							(start 0.2794 -0.1778)
							(mid 0.249642 -0.249642)
							(end 0.1778 -0.2794)
						)
					)
					(width 0)
					(fill yes)
				)
			)
		)
	)
	(footprint ""
		(layer "F.Cu")
		(at 86.233 -11.811)
		(property "Reference" "PL11"
			(at 0 0 0)
			(layer "F.SilkS")
			(hide yes)
			(effects
				(font
					(size 1.27 1.27)
				)
			)
		)
		(property "Value" "IND-D47UH-22-GP"
			(at -5.08 -0.4572 0)
			(unlocked yes)
			(layer "F.Fab")
			(hide yes)
			(effects
				(font
					(size 1.016 1.016)
					(thickness 0.1524)
				)
			)
		)
		(property "Device Type" "L736630H119"
			(at -5.08 -1.9812 0)
			(unlocked yes)
			(layer "F.Fab")
			(hide yes)
			(effects
				(font
					(size 1.016 1.016)
					(thickness 0.1524)
				)
			)
		)
		(duplicate_pad_numbers_are_jumpers no)
		(fp_line
			(start -3.556 -4.4196)
			(end -3.556 4.4196)
			(stroke
				(width 0.1524)
				(type default)
			)
			(layer "F.SilkS")
		)
		(fp_line
			(start -3.556 4.4196)
			(end 3.556 4.4196)
			(stroke
				(width 0.1524)
				(type default)
			)
			(layer "F.SilkS")
		)
		(fp_line
			(start 3.556 -4.4196)
			(end -3.556 -4.4196)
			(stroke
				(width 0.1524)
				(type default)
			)
			(layer "F.SilkS")
		)
		(fp_line
			(start 3.556 4.4196)
			(end 3.556 -4.4196)
			(stroke
				(width 0.1524)
				(type default)
			)
			(layer "F.SilkS")
		)
		(fp_rect
			(start -3.81 4.4958)
			(end 3.81 -4.4958)
			(stroke
				(width 0)
				(type default)
			)
			(fill no)
			(layer "F.CrtYd")
		)
		(fp_rect
			(start -3.81 4.4958)
			(end 3.81 -4.4958)
			(stroke
				(width 0)
				(type default)
			)
			(fill no)
			(layer "F.Fab")
		)
		(pad "1" smd rect
			(at 0 -2.8194)
			(size 3.2512 2.7432)
			(layers "F.Cu" "F.Mask" "F.Paste")
			(net "VT235_VX")
		)
		(pad "2" smd rect
			(at 0 2.8194)
			(size 3.2512 2.7432)
			(layers "F.Cu" "F.Mask" "F.Paste")
			(net "P0V955_C")
		)
	)
	(footprint ""
		(layer "F.Cu")
		(at 274.193 -171.577 90)
		(property "Reference" "R238"
			(at 0 0 90)
			(layer "F.SilkS")
			(hide yes)
			(effects
				(font
					(size 1.27 1.27)
				)
			)
		)
		(property "Value" "0R2J-2-GP"
			(at 0.064008 -3.993896 90)
			(unlocked yes)
			(layer "F.Fab")
			(hide yes)
			(effects
				(font
					(size 1.016 1.016)
					(thickness 0.1524)
				)
			)
		)
		(property "Device Type" "R402H16"
			(at 0.064008 -5.517896 90)
			(unlocked yes)
			(layer "F.Fab")
			(hide yes)
			(effects
				(font
					(size 1.016 1.016)
					(thickness 0.1524)
				)
			)
		)
		(duplicate_pad_numbers_are_jumpers no)
		(fp_line
			(start 0.508 -0.9398)
			(end -0.508 -0.9398)
			(stroke
				(width 0.1524)
				(type default)
			)
			(layer "F.SilkS")
		)
		(fp_line
			(start -0.508 -0.9398)
			(end -0.508 0.9398)
			(stroke
				(width 0.1524)
				(type default)
			)
			(layer "F.SilkS")
		)
		(fp_rect
			(start -0.508 0.9398)
			(end 0.508 -0.9398)
			(stroke
				(width 0)
				(type default)
			)
			(fill no)
			(layer "F.CrtYd")
		)
		(fp_rect
			(start -0.508 0.9398)
			(end 0.508 -0.9398)
			(stroke
				(width 0)
				(type default)
			)
			(fill no)
			(layer "F.Fab")
		)
		(pad "1" smd custom
			(at 0 -0.4445 90)
			(size 0.1397 0.1397)
			(layers "F.Cu" "F.Mask" "F.Paste")
			(net "BMC_MBC_I2C_E_SCL")
			(options
				(clearance outline)
				(anchor circle)
			)
			(primitives
				(gr_poly
					(pts
						(arc
							(start -0.1778 -0.2794)
							(mid -0.249642 -0.249642)
							(end -0.2794 -0.1778)
						)
						(arc
							(start -0.2794 0.1778)
							(mid -0.249642 0.249642)
							(end -0.1778 0.2794)
						)
						(arc
							(start 0.1778 0.2794)
							(mid 0.249642 0.249642)
							(end 0.2794 0.1778)
						)
						(arc
							(start 0.2794 -0.1778)
							(mid 0.249642 -0.249642)
							(end 0.1778 -0.2794)
						)
					)
					(width 0)
					(fill yes)
				)
			)
		)
		(pad "2" smd custom
			(at 0 0.4445 90)
			(size 0.1397 0.1397)
			(layers "F.Cu" "F.Mask" "F.Paste")
			(net "BMC0_SMB1_CLK")
			(options
				(clearance outline)
				(anchor circle)
			)
			(primitives
				(gr_poly
					(pts
						(arc
							(start -0.1778 -0.2794)
							(mid -0.249642 -0.249642)
							(end -0.2794 -0.1778)
						)
						(arc
							(start -0.2794 0.1778)
							(mid -0.249642 0.249642)
							(end -0.1778 0.2794)
						)
						(arc
							(start 0.1778 0.2794)
							(mid 0.249642 0.249642)
							(end 0.2794 0.1778)
						)
						(arc
							(start 0.2794 -0.1778)
							(mid 0.249642 -0.249642)
							(end 0.1778 -0.2794)
						)
					)
					(width 0)
					(fill yes)
				)
			)
		)
	)
)
